(kicad_pcb
	(version 20241229)
	(generator "pcbnew")
	(generator_version "9.0")
	(general
		(thickness 1.6296)
		(legacy_teardrops no)
	)
	(paper "A3")
	(title_block
		(title "Thunderbolt to 10GbE adapter")
		(date "2026-04-21")
		(rev "1.1.0")
		(company "Antmicro Ltd")
		(comment 1 "www.antmicro.com")
		(comment 9 "footprints 304-308 of 703")
	)
	(layers
		(0 "F.Cu" signal)
		(4 "In1.Cu" signal)
		(6 "In2.Cu" signal)
		(8 "In3.Cu" signal)
		(10 "In4.Cu" signal)
		(12 "In5.Cu" signal)
		(14 "In6.Cu" signal)
		(2 "B.Cu" signal)
		(9 "F.Adhes" user "F.Adhesive")
		(11 "B.Adhes" user "B.Adhesive")
		(13 "F.Paste" user)
		(15 "B.Paste" user)
		(5 "F.SilkS" user "F.Silkscreen")
		(7 "B.SilkS" user "B.Silkscreen")
		(1 "F.Mask" user)
		(3 "B.Mask" user)
		(17 "Dwgs.User" user "User.Drawings")
		(19 "Cmts.User" user "User.Comments")
		(21 "Eco1.User" user "User.Eco1")
		(23 "Eco2.User" user "User.Eco2")
		(25 "Edge.Cuts" user)
		(27 "Margin" user)
		(31 "F.CrtYd" user "F.Courtyard")
		(29 "B.CrtYd" user "B.Courtyard")
		(35 "F.Fab" user)
		(33 "B.Fab" user)
	)
	(footprint "antmicro-footprints:C_0402_1005Metric"
		(layer "F.Cu")
		(at 147.2 111.85)
		(descr "Capacitor SMD 0402")
		(tags "capacitor SMD 0402")
		(property "Reference" "C118"
			(at 14.850002 16.75 0)
			(layer "F.SilkS")
			(effects
				(font
					(size 0.7 0.7)
					(thickness 0.15)
				)
			)
		)
		(property "Value" "C_100n_0402"
			(at -1.022927 2.155213 0)
			(layer "F.Fab")
			(effects
				(font
					(size 0.7 0.7)
					(thickness 0.15)
				)
				(justify left bottom)
			)
		)
		(property "Datasheet" "https://www.murata.com/products/productdetail?partno=GRM155R61H104KE14%23"
			(at 0 0 0)
			(layer "F.Fab")
			(hide yes)
			(effects
				(font
					(size 1.27 1.27)
					(thickness 0.15)
				)
			)
		)
		(property "Description" "SMD Multilayer Ceramic Capacitor, 0.1 µF, 50 V, 0402 [1005 Metric], ± 10%, X5R, GRM Series"
			(at 0 0 0)
			(layer "F.Fab")
			(hide yes)
			(effects
				(font
					(size 1.27 1.27)
					(thickness 0.15)
				)
			)
		)
		(property "MPN" "GRM155R61H104KE14D"
			(at 0 0 0)
			(unlocked yes)
			(layer "F.Fab")
			(hide yes)
			(effects
				(font
					(size 1 1)
					(thickness 0.15)
				)
			)
		)
		(property "Manufacturer" "Murata"
			(at 0 0 0)
			(unlocked yes)
			(layer "F.Fab")
			(hide yes)
			(effects
				(font
					(size 1 1)
					(thickness 0.15)
				)
			)
		)
		(property "License" "Apache-2.0"
			(at 0 0 0)
			(unlocked yes)
			(layer "F.Fab")
			(hide yes)
			(effects
				(font
					(size 1 1)
					(thickness 0.15)
				)
			)
		)
		(property "Author" "Antmicro"
			(at 0 0 0)
			(unlocked yes)
			(layer "F.Fab")
			(hide yes)
			(effects
				(font
					(size 1 1)
					(thickness 0.15)
				)
			)
		)
		(property "Val" "100n"
			(at 0 0 0)
			(unlocked yes)
			(layer "F.Fab")
			(hide yes)
			(effects
				(font
					(size 1 1)
					(thickness 0.15)
				)
			)
		)
		(property "Voltage" "50V"
			(at 0 0 0)
			(unlocked yes)
			(layer "F.Fab")
			(hide yes)
			(effects
				(font
					(size 1 1)
					(thickness 0.15)
				)
			)
		)
		(property "Dielectric" "X5R"
			(at 0 0 0)
			(unlocked yes)
			(layer "F.Fab")
			(hide yes)
			(effects
				(font
					(size 1 1)
					(thickness 0.15)
				)
			)
		)
		(sheetname "/X710 DCDC converters/")
		(sheetfile "DCDC_converters_X710.kicad_sch")
		(attr smd)
		(fp_rect
			(start -0.925 -0.47)
			(end 0.925 0.47)
			(stroke
				(width 0.05)
				(type default)
			)
			(fill no)
			(layer "F.CrtYd")
		)
		(fp_line
			(start -0.494 -0.25)
			(end 0.504 -0.25)
			(stroke
				(width 0.15)
				(type solid)
			)
			(layer "F.Fab")
		)
		(fp_line
			(start -0.494 0.248)
			(end -0.494 -0.25)
			(stroke
				(width 0.15)
				(type solid)
			)
			(layer "F.Fab")
		)
		(fp_line
			(start 0.504 -0.25)
			(end 0.504 0.248)
			(stroke
				(width 0.15)
				(type solid)
			)
			(layer "F.Fab")
		)
		(fp_line
			(start 0.504 0.248)
			(end -0.494 0.248)
			(stroke
				(width 0.15)
				(type solid)
			)
			(layer "F.Fab")
		)
		(fp_text user "License: Apache-2.0"
			(at -0.939 5.799 0)
			(layer "F.Fab")
			(effects
				(font
					(size 0.7 0.7)
					(thickness 0.15)
				)
				(justify left bottom)
			)
		)
		(fp_text user "${REFERENCE}"
			(at -0.939 4.599 0)
			(layer "F.Fab")
			(effects
				(font
					(size 0.7 0.7)
					(thickness 0.15)
				)
				(justify left bottom)
			)
		)
		(fp_text user "Author: Antmicro"
			(at -0.939 3.399 0)
			(layer "F.Fab")
			(effects
				(font
					(size 0.7 0.7)
					(thickness 0.15)
				)
				(justify left bottom)
			)
		)
		(pad "1" smd roundrect
			(at -0.48 0)
			(size 0.59 0.64)
			(layers "F.Cu" "F.Mask" "F.Paste")
			(roundrect_rratio 0.25)
			(net 23 "GND")
			(pintype "passive")
		)
		(pad "2" smd roundrect
			(at 0.48 0)
			(size 0.59 0.64)
			(layers "F.Cu" "F.Mask" "F.Paste")
			(roundrect_rratio 0.25)
			(net 40 "+5V")
			(pintype "passive")
		)
	)
	(footprint "antmicro-footprints:R_0402_1005Metric"
		(layer "F.Cu")
		(at 125 54.5)
		(descr "Resistor SMD 0402")
		(tags "resistor SMD 0402")
		(property "Reference" "R233"
			(at -5.75 0.5 0)
			(layer "F.SilkS")
			(effects
				(font
					(size 0.7 0.7)
					(thickness 0.15)
				)
				(justify left bottom)
			)
		)
		(property "Value" "R_470R_0402"
			(at -1.011843 1.772047 0)
			(layer "F.Fab")
			(effects
				(font
					(size 0.7 0.7)
					(thickness 0.15)
				)
				(justify left bottom)
			)
		)
		(property "Datasheet" "https://www.bourns.com/docs/product-datasheets/cr.pdf"
			(at 0 0 0)
			(layer "F.Fab")
			(hide yes)
			(effects
				(font
					(size 1.27 1.27)
					(thickness 0.15)
				)
			)
		)
		(property "Description" "SMD Chip Resistor, 470 ohm, ± 1%, 62.5 mW, 0402 [1005 Metric], Thick Film, General Purpose"
			(at 0 0 0)
			(layer "F.Fab")
			(hide yes)
			(effects
				(font
					(size 1.27 1.27)
					(thickness 0.15)
				)
			)
		)
		(property "MPN" "CR0402-FX-4700GLF"
			(at 0 0 0)
			(unlocked yes)
			(layer "F.Fab")
			(hide yes)
			(effects
				(font
					(size 1 1)
					(thickness 0.15)
				)
			)
		)
		(property "Manufacturer" "Bourns"
			(at 0 0 0)
			(unlocked yes)
			(layer "F.Fab")
			(hide yes)
			(effects
				(font
					(size 1 1)
					(thickness 0.15)
				)
			)
		)
		(property "License" "Apache-2.0"
			(at 0 0 0)
			(unlocked yes)
			(layer "F.Fab")
			(hide yes)
			(effects
				(font
					(size 1 1)
					(thickness 0.15)
				)
			)
		)
		(property "Author" "Antmicro"
			(at 0 0 0)
			(unlocked yes)
			(layer "F.Fab")
			(hide yes)
			(effects
				(font
					(size 1 1)
					(thickness 0.15)
				)
			)
		)
		(property "Val" "470R"
			(at 0 0 0)
			(unlocked yes)
			(layer "F.Fab")
			(hide yes)
			(effects
				(font
					(size 1 1)
					(thickness 0.15)
				)
			)
		)
		(property "Tolerance" "1%"
			(at 0 0 0)
			(unlocked yes)
			(layer "F.Fab")
			(hide yes)
			(effects
				(font
					(size 1 1)
					(thickness 0.15)
				)
			)
		)
		(sheetname "/Power input/")
		(sheetfile "power_input.kicad_sch")
		(attr smd)
		(fp_rect
			(start -0.925 -0.47)
			(end 0.925 0.47)
			(stroke
				(width 0.05)
				(type default)
			)
			(fill no)
			(layer "F.CrtYd")
		)
		(fp_rect
			(start -0.5 -0.25)
			(end 0.5 0.25)
			(stroke
				(width 0.15)
				(type solid)
			)
			(fill no)
			(layer "F.Fab")
		)
		(fp_text user "${REFERENCE}"
			(at -0.95 3.168 0)
			(layer "F.Fab")
			(effects
				(font
					(size 0.7 0.7)
					(thickness 0.15)
				)
				(justify left bottom)
			)
		)
		(fp_text user "Author: Antmicro"
			(at -0.95 4.169 0)
			(layer "F.Fab")
			(effects
				(font
					(size 0.7 0.7)
					(thickness 0.15)
				)
				(justify left bottom)
			)
		)
		(fp_text user "License: Apache-2.0"
			(at -0.95 5.169 0)
			(layer "F.Fab")
			(effects
				(font
					(size 0.7 0.7)
					(thickness 0.15)
				)
				(justify left bottom)
			)
		)
		(pad "1" smd roundrect
			(at -0.48 0)
			(size 0.59 0.64)
			(layers "F.Cu" "F.Mask" "F.Paste")
			(roundrect_rratio 0.25)
			(net 420 "Net-(D16-A)")
			(pintype "passive")
		)
		(pad "2" smd roundrect
			(at 0.48 0)
			(size 0.59 0.64)
			(layers "F.Cu" "F.Mask" "F.Paste")
			(roundrect_rratio 0.25)
			(net 349 "/Power input/5V_OUT")
			(pintype "passive")
		)
	)
	(footprint "antmicro-footprints:C_0603_1608Metric_EIA"
		(layer "F.Cu")
		(at 144.15 103.050002 -90)
		(descr "Capacitor SMD 0603, IPC-7351 Density Level A")
		(tags "Capacitor 0603")
		(property "Reference" "C148"
			(at 17.649996 -15.649999 270)
			(layer "F.SilkS")
			(effects
				(font
					(size 0.7 0.7)
					(thickness 0.15)
				)
			)
		)
		(property "Value" "C_22u_16V_0603"
			(at -1.42757 1.770288 270)
			(layer "F.Fab")
			(effects
				(font
					(size 0.7 0.7)
					(thickness 0.15)
				)
				(justify left bottom)
			)
		)
		(property "Datasheet" "https://product.samsungsem.com/mlcc/CL10A226MO7JZN.do"
			(at 0 0 270)
			(layer "F.Fab")
			(hide yes)
			(effects
				(font
					(size 1.27 1.27)
					(thickness 0.15)
				)
			)
		)
		(property "Description" "SMD Multilayer Ceramic Capacitor"
			(at 0 0 270)
			(layer "F.Fab")
			(hide yes)
			(effects
				(font
					(size 1.27 1.27)
					(thickness 0.15)
				)
			)
		)
		(property "MPN" "CL10A226MO7JZNC"
			(at 0 0 270)
			(unlocked yes)
			(layer "F.Fab")
			(hide yes)
			(effects
				(font
					(size 1 1)
					(thickness 0.15)
				)
			)
		)
		(property "Manufacturer" "Samsung Electro-Mechanics"
			(at 0 0 270)
			(unlocked yes)
			(layer "F.Fab")
			(hide yes)
			(effects
				(font
					(size 1 1)
					(thickness 0.15)
				)
			)
		)
		(property "License" "Apache-2.0"
			(at 0 0 270)
			(unlocked yes)
			(layer "F.Fab")
			(hide yes)
			(effects
				(font
					(size 1 1)
					(thickness 0.15)
				)
			)
		)
		(property "Author" "Antmicro"
			(at 0 0 270)
			(unlocked yes)
			(layer "F.Fab")
			(hide yes)
			(effects
				(font
					(size 1 1)
					(thickness 0.15)
				)
			)
		)
		(property "Val" "22u"
			(at 0 0 270)
			(unlocked yes)
			(layer "F.Fab")
			(hide yes)
			(effects
				(font
					(size 1 1)
					(thickness 0.15)
				)
			)
		)
		(property "Voltage" "16V"
			(at 0 0 270)
			(unlocked yes)
			(layer "F.Fab")
			(hide yes)
			(effects
				(font
					(size 1 1)
					(thickness 0.15)
				)
			)
		)
		(property "Dielectric" ""
			(at 0 0 270)
			(unlocked yes)
			(layer "F.Fab")
			(hide yes)
			(effects
				(font
					(size 1 1)
					(thickness 0.15)
				)
			)
		)
		(sheetname "/X710 DCDC converters/")
		(sheetfile "DCDC_converters_X710.kicad_sch")
		(attr smd)
		(fp_line
			(start -0.15 0.55)
			(end 0.15 0.55)
			(stroke
				(width 0.15)
				(type solid)
			)
			(layer "F.SilkS")
		)
		(fp_line
			(start -0.15 -0.55)
			(end 0.15 -0.55)
			(stroke
				(width 0.15)
				(type solid)
			)
			(layer "F.SilkS")
		)
		(fp_rect
			(start -1.25 -0.65)
			(end 1.25 0.65)
			(stroke
				(width 0.05)
				(type solid)
			)
			(fill no)
			(layer "F.CrtYd")
		)
		(fp_rect
			(start -0.8 -0.45)
			(end 0.8 0.45)
			(stroke
				(width 0.15)
				(type solid)
			)
			(fill no)
			(layer "F.Fab")
		)
		(fp_text user "${REFERENCE}"
			(at -1.682 3.895 270)
			(layer "F.Fab")
			(effects
				(font
					(size 0.7 0.7)
					(thickness 0.15)
				)
				(justify left bottom)
			)
		)
		(fp_text user "Author: Antmicro"
			(at -1.682 4.894 270)
			(layer "F.Fab")
			(effects
				(font
					(size 0.7 0.7)
					(thickness 0.15)
				)
				(justify left bottom)
			)
		)
		(fp_text user "License: Apache-2.0"
			(at -1.682 5.895 270)
			(layer "F.Fab")
			(effects
				(font
					(size 0.7 0.7)
					(thickness 0.15)
				)
				(justify left bottom)
			)
		)
		(pad "1" smd roundrect
			(at -0.7 0 270)
			(size 0.8 1.1)
			(layers "F.Cu" "F.Mask" "F.Paste")
			(roundrect_rratio 0.2)
			(net 23 "GND")
			(pintype "passive")
		)
		(pad "2" smd roundrect
			(at 0.7 0 270)
			(size 0.8 1.1)
			(layers "F.Cu" "F.Mask" "F.Paste")
			(roundrect_rratio 0.2)
			(net 341 "/X710 DCDC converters/+DVDD_OUT")
			(pintype "passive")
		)
	)
	(footprint "antmicro-footprints:Resonator_SMD_Murata_XRCGB_2x1.6x0.65mm"
		(layer "F.Cu")
		(at 157.225 97.080499 -90)
		(property "Reference" "Y3"
			(at 19.625001 -23.299999 90)
			(layer "F.SilkS")
			(effects
				(font
					(size 0.7 0.7)
					(thickness 0.15)
				)
			)
		)
		(property "Value" "Resonator_50MHz_XRCGE"
			(at 0 2.2 270)
			(layer "F.Fab")
			(effects
				(font
					(size 0.7 0.7)
					(thickness 0.15)
				)
				(justify left bottom)
			)
		)
		(property "Datasheet" "https://www.murata.com/products/productdata/8813268205598/SPEC-XRCGE50M000F5A2AR0.pdf"
			(at 0 0 270)
			(layer "F.Fab")
			(hide yes)
			(effects
				(font
					(size 1.27 1.27)
					(thickness 0.15)
				)
			)
		)
		(property "Description" "Crystal, 50 MHz, 2mm x 1.6mm, 50 ppm, 4.7 pF, 50 ppm, XRCGE Series"
			(at 0 0 270)
			(layer "F.Fab")
			(hide yes)
			(effects
				(font
					(size 1.27 1.27)
					(thickness 0.15)
				)
			)
		)
		(property "Manufacturer" "Murata"
			(at 0 0 270)
			(unlocked yes)
			(layer "F.Fab")
			(hide yes)
			(effects
				(font
					(size 1 1)
					(thickness 0.15)
				)
			)
		)
		(property "MPN" "XRCGE50M000F5A2AR0"
			(at 0 0 270)
			(unlocked yes)
			(layer "F.Fab")
			(hide yes)
			(effects
				(font
					(size 1 1)
					(thickness 0.15)
				)
			)
		)
		(property "Val" "50MHz"
			(at 0 0 270)
			(unlocked yes)
			(layer "F.Fab")
			(hide yes)
			(effects
				(font
					(size 1 1)
					(thickness 0.15)
				)
			)
		)
		(property "CLoad" "4.7pF"
			(at 0 0 270)
			(unlocked yes)
			(layer "F.Fab")
			(hide yes)
			(effects
				(font
					(size 1 1)
					(thickness 0.15)
				)
			)
		)
		(property "Author" "Antmicro"
			(at 0 0 270)
			(unlocked yes)
			(layer "F.Fab")
			(hide yes)
			(effects
				(font
					(size 1 1)
					(thickness 0.15)
				)
			)
		)
		(property "License" "Apache-2.0"
			(at 0 0 270)
			(unlocked yes)
			(layer "F.Fab")
			(hide yes)
			(effects
				(font
					(size 1 1)
					(thickness 0.15)
				)
			)
		)
		(sheetname "/X710-AT2 Misc/")
		(sheetfile "x710-at2-mics.kicad_sch")
		(attr smd)
		(fp_line
			(start -0.4 1.15)
			(end 0.4 1.15)
			(stroke
				(width 0.15)
				(type solid)
			)
			(layer "F.SilkS")
		)
		(fp_line
			(start -0.95 0.4)
			(end -0.95 -0.4)
			(stroke
				(width 0.15)
				(type solid)
			)
			(layer "F.SilkS")
		)
		(fp_line
			(start 0.95 0.4)
			(end 0.95 -0.4)
			(stroke
				(width 0.15)
				(type solid)
			)
			(layer "F.SilkS")
		)
		(fp_line
			(start -0.4 -1.15)
			(end 0.4 -1.15)
			(stroke
				(width 0.15)
				(type solid)
			)
			(layer "F.SilkS")
		)
		(fp_circle
			(center -0.95 -1.15)
			(end -0.9 -1.15)
			(stroke
				(width 0.15)
				(type solid)
			)
			(fill yes)
			(layer "F.SilkS")
		)
		(fp_rect
			(start -1.05 -1.25)
			(end 1.05 1.24)
			(stroke
				(width 0.05)
				(type solid)
			)
			(fill no)
			(layer "F.CrtYd")
		)
		(fp_rect
			(start -0.85 -1.054)
			(end 0.852 1.054)
			(stroke
				(width 0.15)
				(type solid)
			)
			(fill no)
			(layer "F.Fab")
		)
		(fp_text user "License: Apache-2.0"
			(at -1.05 5.8 270)
			(layer "F.Fab")
			(effects
				(font
					(size 0.7 0.7)
					(thickness 0.15)
				)
				(justify left bottom)
			)
		)
		(fp_text user "${REFERENCE}"
			(at -1.05 3.4 270)
			(layer "F.Fab")
			(effects
				(font
					(size 0.7 0.7)
					(thickness 0.15)
				)
				(justify left bottom)
			)
		)
		(fp_text user "Author: Antmicro"
			(at -1.05 4.6 270)
			(layer "F.Fab")
			(effects
				(font
					(size 0.7 0.7)
					(thickness 0.15)
				)
				(justify left bottom)
			)
		)
		(pad "1" smd rect
			(at -0.5 -0.675 270)
			(size 0.7 0.75)
			(layers "F.Cu" "F.Mask" "F.Paste")
			(net 58 "/X710-AT2 Misc/50MHZ_XTAL_R.+")
			(pintype "passive")
		)
		(pad "2" smd rect
			(at -0.5 0.675 270)
			(size 0.7 0.75)
			(layers "F.Cu" "F.Mask" "F.Paste")
			(net 23 "GND")
			(pinfunction "SH")
			(pintype "passive")
		)
		(pad "3" smd rect
			(at 0.5 0.675 270)
			(size 0.7 0.75)
			(layers "F.Cu" "F.Mask" "F.Paste")
			(net 59 "/X710-AT2 Misc/50MHZ_XTAL_R.-")
			(pintype "passive")
		)
		(pad "4" smd rect
			(at 0.5 -0.675 270)
			(size 0.7 0.75)
			(layers "F.Cu" "F.Mask" "F.Paste")
			(net 23 "GND")
			(pinfunction "SH")
			(pintype "passive")
		)
	)
	(footprint "antmicro-footprints:R_0402_1005Metric"
		(layer "F.Cu")
		(at 142.310001 94.674999 180)
		(descr "Resistor SMD 0402")
		(tags "resistor SMD 0402")
		(property "Reference" "R182"
			(at -2.190001 -0.025001 180)
			(layer "F.SilkS")
			(effects
				(font
					(size 0.7 0.7)
					(thickness 0.15)
				)
			)
		)
		(property "Value" "R_10k_0402"
			(at -1.011843 1.772047 180)
			(layer "F.Fab")
			(effects
				(font
					(size 0.7 0.7)
					(thickness 0.15)
				)
				(justify left bottom)
			)
		)
		(property "Datasheet" "https://www.bourns.com/docs/product-datasheets/cr.pdf"
			(at 0 0 180)
			(layer "F.Fab")
			(hide yes)
			(effects
				(font
					(size 1.27 1.27)
					(thickness 0.15)
				)
			)
		)
		(property "Description" "SMD Chip Resistor, 10 kohm, ± 1%, 62.5 mW, 0402 [1005 Metric], Thick Film, General Purpose"
			(at 0 0 180)
			(layer "F.Fab")
			(hide yes)
			(effects
				(font
					(size 1.27 1.27)
					(thickness 0.15)
				)
			)
		)
		(property "MPN" "CR0402-FX-1002GLF"
			(at 0 0 180)
			(unlocked yes)
			(layer "F.Fab")
			(hide yes)
			(effects
				(font
					(size 1 1)
					(thickness 0.15)
				)
			)
		)
		(property "Manufacturer" "Bourns"
			(at 0 0 180)
			(unlocked yes)
			(layer "F.Fab")
			(hide yes)
			(effects
				(font
					(size 1 1)
					(thickness 0.15)
				)
			)
		)
		(property "License" "Apache-2.0"
			(at 0 0 180)
			(unlocked yes)
			(layer "F.Fab")
			(hide yes)
			(effects
				(font
					(size 1 1)
					(thickness 0.15)
				)
			)
		)
		(property "Author" "Antmicro"
			(at 0 0 180)
			(unlocked yes)
			(layer "F.Fab")
			(hide yes)
			(effects
				(font
					(size 1 1)
					(thickness 0.15)
				)
			)
		)
		(property "Val" "10k"
			(at 0 0 180)
			(unlocked yes)
			(layer "F.Fab")
			(hide yes)
			(effects
				(font
					(size 1 1)
					(thickness 0.15)
				)
			)
		)
		(property "Tolerance" "1%"
			(at 0 0 180)
			(unlocked yes)
			(layer "F.Fab")
			(hide yes)
			(effects
				(font
					(size 1 1)
					(thickness 0.15)
				)
			)
		)
		(sheetname "/X710-AT2 Misc/")
		(sheetfile "x710-at2-mics.kicad_sch")
		(attr smd)
		(fp_rect
			(start -0.925 -0.47)
			(end 0.925 0.47)
			(stroke
				(width 0.05)
				(type default)
			)
			(fill no)
			(layer "F.CrtYd")
		)
		(fp_rect
			(start -0.5 -0.25)
			(end 0.5 0.25)
			(stroke
				(width 0.15)
				(type solid)
			)
			(fill no)
			(layer "F.Fab")
		)
		(fp_text user "${REFERENCE}"
			(at -0.95 3.168 180)
			(layer "F.Fab")
			(effects
				(font
					(size 0.7 0.7)
					(thickness 0.15)
				)
				(justify left bottom)
			)
		)
		(fp_text user "License: Apache-2.0"
			(at -0.95 5.169 180)
			(layer "F.Fab")
			(effects
				(font
					(size 0.7 0.7)
					(thickness 0.15)
				)
				(justify left bottom)
			)
		)
		(fp_text user "Author: Antmicro"
			(at -0.95 4.169 180)
			(layer "F.Fab")
			(effects
				(font
					(size 0.7 0.7)
					(thickness 0.15)
				)
				(justify left bottom)
			)
		)
		(pad "1" smd roundrect
			(at -0.48 0 180)
			(size 0.59 0.64)
			(layers "F.Cu" "F.Mask" "F.Paste")
			(roundrect_rratio 0.25)
			(net 350 "/X710 flash memory/FLASH.~{CE}")
			(pintype "passive")
		)
		(pad "2" smd roundrect
			(at 0.48 0 180)
			(size 0.59 0.64)
			(layers "F.Cu" "F.Mask" "F.Paste")
			(roundrect_rratio 0.25)
			(net 7 "+3V3")
			(pintype "passive")
		)
	)
)
